(kicad_pcb
	(version 20260206)
	(generator "pcbnew")
	(generator_version "10.0")
	(general
		(thickness 1.6)
		(legacy_teardrops no)
	)
	(paper "A4")
	(title_block
		(title "v1-chassis-manager — T6M_CM_d_v01_1031_1645.brd")
		(comment 1 "Open CloudServer (Microsoft) / footprints 77-80 of 2512")
	)
	(layers
		(0 "F.Cu" signal "TOP")
		(4 "In1.Cu" signal "GND1")
		(6 "In2.Cu" signal "IN1")
		(8 "In3.Cu" signal "VCC1")
		(10 "In4.Cu" signal "VCC2")
		(12 "In5.Cu" signal "GND2")
		(14 "In6.Cu" signal "IN2")
		(16 "In7.Cu" signal "IN3")
		(18 "In8.Cu" signal "GND3")
		(2 "B.Cu" signal "BOTTOM")
		(9 "F.Adhes" user "F.Adhesive")
		(11 "B.Adhes" user "B.Adhesive")
		(13 "F.Paste" user "Package Geometry/Pastemask Top")
		(15 "B.Paste" user "Package Geometry/Pastemask Bottom")
		(5 "F.SilkS" user "Ref Des/Silkscreen Top")
		(7 "B.SilkS" user "Ref Des/Silkscreen Bottom")
		(1 "F.Mask" user "Board Geometry/Soldermask Top")
		(3 "B.Mask" user "Board Geometry/Soldermask Bottom")
		(17 "Dwgs.User" user "User.Drawings")
		(19 "Cmts.User" user "User.Comments")
		(21 "Eco1.User" user "User.Eco1")
		(23 "Eco2.User" user "User.Eco2")
		(25 "Edge.Cuts" user "Board Geometry/Outline")
		(27 "Margin" user)
		(31 "F.CrtYd" user "Package Geometry/Place Bound Top")
		(29 "B.CrtYd" user "Package Geometry/Place Bound Bottom")
		(35 "F.Fab" user "Ref Des/Assembly Top")
		(33 "B.Fab" user "Ref Des/Assembly Bottom")
	)
	(footprint ""
		(layer "F.Cu")
		(at 22.537166 -137.846308)
		(property "Reference" "C430"
			(at -2.122424 3.178048 0)
			(unlocked yes)
			(layer "F.SilkS")
			(effects
				(font
					(size 0.7874 0.5842)
					(thickness 0.1524)
				)
				(justify left)
			)
		)
		(property "Value" ""
			(at 0 0 0)
			(layer "F.Fab")
			(effects
				(font
					(size 1.27 1.27)
				)
			)
		)
		(duplicate_pad_numbers_are_jumpers no)
		(fp_line
			(start -1.905 -0.8636)
			(end 1.905 -0.8636)
			(stroke
				(width 0.1524)
				(type default)
			)
			(layer "F.SilkS")
		)
		(fp_line
			(start -1.905 0.8636)
			(end -1.905 -0.8636)
			(stroke
				(width 0.1524)
				(type default)
			)
			(layer "F.SilkS")
		)
		(fp_line
			(start 0 0.8382)
			(end 0 -0.8382)
			(stroke
				(width 0.1524)
				(type default)
			)
			(layer "F.SilkS")
		)
		(fp_line
			(start 1.905 -0.8636)
			(end 1.905 0.8636)
			(stroke
				(width 0.1524)
				(type default)
			)
			(layer "F.SilkS")
		)
		(fp_line
			(start 1.905 0.8636)
			(end -1.905 0.8636)
			(stroke
				(width 0.1524)
				(type default)
			)
			(layer "F.SilkS")
		)
		(fp_rect
			(start -1.524 0.7366)
			(end 1.524 -0.7366)
			(stroke
				(width 0)
				(type default)
			)
			(fill no)
			(layer "F.CrtYd")
		)
		(pad "1" smd rect
			(at 0.94996 0)
			(size 1.1176 1.3716)
			(layers "F.Cu" "F.Mask" "F.Paste")
			(net "P1V9_LAN1")
		)
		(pad "2" smd rect
			(at -0.94996 0)
			(size 1.1176 1.3716)
			(layers "F.Cu" "F.Mask" "F.Paste")
			(net "GND")
		)
	)
	(footprint ""
		(layer "F.Cu")
		(at 93.963236 -82.994246 90)
		(property "Reference" "Q42"
			(at -2.537206 0.170942 0)
			(unlocked yes)
			(layer "F.SilkS")
			(effects
				(font
					(size 0.7874 0.5842)
					(thickness 0.1524)
				)
				(justify left)
			)
		)
		(property "Value" ""
			(at 0 0 90)
			(layer "F.Fab")
			(effects
				(font
					(size 1.27 1.27)
				)
			)
		)
		(duplicate_pad_numbers_are_jumpers no)
		(fp_line
			(start 2.584196 -0.5842)
			(end 2.584196 2.48412)
			(stroke
				(width 0.1524)
				(type default)
			)
			(layer "F.SilkS")
		)
		(fp_line
			(start -0.5842 -0.5842)
			(end 2.584196 -0.5842)
			(stroke
				(width 0.1524)
				(type default)
			)
			(layer "F.SilkS")
		)
		(fp_line
			(start 2.584196 2.48412)
			(end -0.5842 2.48412)
			(stroke
				(width 0.1524)
				(type default)
			)
			(layer "F.SilkS")
		)
		(fp_line
			(start -0.5842 2.48412)
			(end -0.5842 -0.5842)
			(stroke
				(width 0.1524)
				(type default)
			)
			(layer "F.SilkS")
		)
		(fp_poly
			(pts
				(xy -0.508 -0.4572) (xy 0.299974 -0.4572) (xy 0.299974 -0.54991) (xy 1.700022 -0.54991) (xy 1.700022 0.49276)
				(xy 2.507996 0.49276) (xy 2.507996 1.40716) (xy 1.700022 1.40716) (xy 1.700022 2.450084) (xy 0.299974 2.450084)
				(xy 0.299974 2.35712) (xy -0.508 2.35712)
			)
			(stroke
				(width 0)
				(type default)
			)
			(fill no)
			(layer "F.CrtYd")
		)
		(fp_line
			(start 1.700022 -0.54991)
			(end 1.700022 2.450084)
			(stroke
				(width 0.1)
				(type default)
			)
			(layer "F.Fab")
		)
		(fp_line
			(start 0.299974 -0.54991)
			(end 1.700022 -0.54991)
			(stroke
				(width 0.1)
				(type default)
			)
			(layer "F.Fab")
		)
		(fp_line
			(start 1.700022 2.450084)
			(end 0.299974 2.450084)
			(stroke
				(width 0.1)
				(type default)
			)
			(layer "F.Fab")
		)
		(fp_line
			(start 0.299974 2.450084)
			(end 0.299974 -0.54991)
			(stroke
				(width 0.1)
				(type default)
			)
			(layer "F.Fab")
		)
		(fp_text user "C"
			(at 2.57683 -1.116838 0)
			(unlocked yes)
			(layer "F.SilkS")
			(effects
				(font
					(size 0.635 0.4064)
					(thickness 0.1524)
				)
				(justify left)
			)
		)
		(fp_text user "B"
			(at -1.238758 0.435864 0)
			(unlocked yes)
			(layer "F.SilkS")
			(effects
				(font
					(size 0.635 0.4064)
					(thickness 0.1524)
				)
				(justify left)
			)
		)
		(fp_text user "E"
			(at -1.247394 1.912366 0)
			(unlocked yes)
			(layer "F.SilkS")
			(effects
				(font
					(size 0.635 0.4064)
					(thickness 0.1524)
				)
				(justify left)
			)
		)
		(fp_text user "B"
			(at -1.5494 0.00127 90)
			(unlocked yes)
			(layer "F.Fab")
			(effects
				(font
					(size 0.7874 0.5842)
					(thickness 0.000001)
				)
				(justify left)
			)
		)
		(fp_text user "C"
			(at 2.8702 0.99187 90)
			(unlocked yes)
			(layer "F.Fab")
			(effects
				(font
					(size 0.7874 0.5842)
					(thickness 0.000001)
				)
				(justify left)
			)
		)
		(fp_text user "E"
			(at -1.5748 1.95707 90)
			(unlocked yes)
			(layer "F.Fab")
			(effects
				(font
					(size 0.7874 0.5842)
					(thickness 0.000001)
				)
				(justify left)
			)
		)
		(pad "B" smd rect
			(at 0 0 180)
			(size 0.8128 0.9144)
			(layers "F.Cu" "F.Mask" "F.Paste")
			(net "N45787194")
		)
		(pad "C" smd rect
			(at 1.999996 0.94996 180)
			(size 0.8128 0.9144)
			(layers "F.Cu" "F.Mask" "F.Paste")
			(net "CPU_NODE1_PROCHOT_N")
		)
		(pad "E" smd rect
			(at 0 1.89992 180)
			(size 0.8128 0.9144)
			(layers "F.Cu" "F.Mask" "F.Paste")
			(net "H_CPU_NODE1_PROCHOT_L")
		)
	)
	(footprint ""
		(layer "F.Cu")
		(at 153.526998 -142.88643 -90)
		(property "Reference" "R566"
			(at -1.382014 -0.556514 90)
			(unlocked yes)
			(layer "F.SilkS")
			(effects
				(font
					(size 0.635 0.4064)
					(thickness 0.1524)
				)
				(justify left)
			)
		)
		(property "Value" ""
			(at 0 0 270)
			(layer "F.Fab")
			(effects
				(font
					(size 1.27 1.27)
				)
			)
		)
		(duplicate_pad_numbers_are_jumpers no)
		(fp_line
			(start -0.7874 0.4064)
			(end -0.7874 -0.4064)
			(stroke
				(width 0.1524)
				(type default)
			)
			(layer "F.SilkS")
		)
		(fp_line
			(start 0.7874 0.4064)
			(end -0.7874 0.4064)
			(stroke
				(width 0.1524)
				(type default)
			)
			(layer "F.SilkS")
		)
		(fp_line
			(start -0.7874 -0.4064)
			(end 0.7874 -0.4064)
			(stroke
				(width 0.1524)
				(type default)
			)
			(layer "F.SilkS")
		)
		(fp_line
			(start 0.7874 -0.4064)
			(end 0.7874 0.4064)
			(stroke
				(width 0.1524)
				(type default)
			)
			(layer "F.SilkS")
		)
		(fp_poly
			(pts
				(xy -0.508 0.2794) (xy -0.508 0.2286) (xy -0.635 0.2286) (xy -0.635 -0.254) (xy -0.5334 -0.254)
				(xy -0.5334 -0.2794) (xy 0.5334 -0.2794) (xy 0.5334 -0.254) (xy 0.635 -0.254) (xy 0.635 0.254) (xy 0.5334 0.254)
				(xy 0.5334 0.2794)
			)
			(stroke
				(width 0)
				(type default)
			)
			(fill no)
			(layer "F.CrtYd")
		)
		(pad "1" smd rect
			(at 0.40005 0 270)
			(size 0.4572 0.508)
			(layers "F.Cu" "F.Mask" "F.Paste")
			(net "P3V3_NODE1")
		)
		(pad "2" smd rect
			(at -0.40005 0 270)
			(size 0.4572 0.508)
			(layers "F.Cu" "F.Mask" "F.Paste")
			(net "SMB_LAN2_DAT")
		)
	)
	(footprint ""
		(layer "F.Cu")
		(at 34.474404 -12.03198)
		(property "Reference" "PR34"
			(at -10.784078 -0.04826 0)
			(unlocked yes)
			(layer "F.SilkS")
			(effects
				(font
					(size 0.7874 0.5842)
					(thickness 0.1524)
				)
				(justify left)
			)
		)
		(property "Value" ""
			(at 0 0 0)
			(layer "F.Fab")
			(effects
				(font
					(size 1.27 1.27)
				)
			)
		)
		(duplicate_pad_numbers_are_jumpers no)
		(fp_line
			(start -0.7874 -0.4064)
			(end 0.7874 -0.4064)
			(stroke
				(width 0.1524)
				(type default)
			)
			(layer "F.SilkS")
		)
		(fp_line
			(start -0.7874 0.4064)
			(end -0.7874 -0.4064)
			(stroke
				(width 0.1524)
				(type default)
			)
			(layer "F.SilkS")
		)
		(fp_line
			(start 0.7874 -0.4064)
			(end 0.7874 0.4064)
			(stroke
				(width 0.1524)
				(type default)
			)
			(layer "F.SilkS")
		)
		(fp_line
			(start 0.7874 0.4064)
			(end -0.7874 0.4064)
			(stroke
				(width 0.1524)
				(type default)
			)
			(layer "F.SilkS")
		)
		(fp_poly
			(pts
				(xy -0.508 0.2794) (xy -0.508 0.2286) (xy -0.635 0.2286) (xy -0.635 -0.254) (xy -0.5334 -0.254)
				(xy -0.5334 -0.2794) (xy 0.5334 -0.2794) (xy 0.5334 -0.254) (xy 0.635 -0.254) (xy 0.635 0.254) (xy 0.5334 0.254)
				(xy 0.5334 0.2794)
			)
			(stroke
				(width 0)
				(type default)
			)
			(fill no)
			(layer "F.CrtYd")
		)
		(pad "1" smd rect
			(at 0.40005 0)
			(size 0.4572 0.508)
			(layers "F.Cu" "F.Mask" "F.Paste")
			(net "VSENSE_PV_VDDR_NODE1_N")
		)
		(pad "2" smd rect
			(at -0.40005 0)
			(size 0.4572 0.508)
			(layers "F.Cu" "F.Mask" "F.Paste")
			(net "GND")
		)
	)
)
